(kicad_pcb
	(version 20241229)
	(generator "pcbnew")
	(generator_version "9.0")
	(general
		(thickness 1.62)
		(legacy_teardrops no)
	)
	(paper "A3")
	(title_block
		(title "COM Express 7 Baseboard")
		(date "2025-02-04")
		(rev "1.1.2")
		(company "Antmicro Ltd")
		(comment 1 "www.antmicro.com")
		(comment 9 "footprints 397-401 of 802")
	)
	(layers
		(0 "F.Cu" signal)
		(4 "In1.Cu" signal)
		(6 "In2.Cu" signal)
		(8 "In3.Cu" signal)
		(10 "In4.Cu" signal)
		(12 "In5.Cu" signal)
		(14 "In6.Cu" signal)
		(2 "B.Cu" signal)
		(9 "F.Adhes" user "F.Adhesive")
		(11 "B.Adhes" user "B.Adhesive")
		(13 "F.Paste" user)
		(15 "B.Paste" user)
		(5 "F.SilkS" user "F.Silkscreen")
		(7 "B.SilkS" user "B.Silkscreen")
		(1 "F.Mask" user)
		(3 "B.Mask" user)
		(17 "Dwgs.User" user "User.Drawings")
		(19 "Cmts.User" user "User.Comments")
		(21 "Eco1.User" user "User.Eco1")
		(23 "Eco2.User" user "User.Eco2")
		(25 "Edge.Cuts" user)
		(27 "Margin" user)
		(31 "F.CrtYd" user "F.Courtyard")
		(29 "B.CrtYd" user "B.Courtyard")
		(35 "F.Fab" user)
		(33 "B.Fab" user)
	)
	(footprint "antmicro-footprints:TP_SMD_0.75mm"
		(layer "F.Cu")
		(at 128.44 128.71)
		(property "Reference" "TP94"
			(at 0.51 -3.3 90)
			(layer "F.SilkS")
			(effects
				(font
					(size 0.7 0.7)
					(thickness 0.15)
				)
				(justify left bottom)
			)
		)
		(property "Value" "TP_0.75mm_SMD"
			(at 0 1.2 0)
			(layer "F.Fab")
			(effects
				(font
					(size 0.7 0.7)
					(thickness 0.15)
				)
				(justify left bottom)
			)
		)
		(property "Author" "Antmicro"
			(at 0 0 0)
			(layer "F.Fab")
			(hide yes)
			(effects
				(font
					(size 1 1)
					(thickness 0.15)
				)
			)
		)
		(property "License" "Apache-2.0"
			(at 0 0 0)
			(layer "F.Fab")
			(hide yes)
			(effects
				(font
					(size 1 1)
					(thickness 0.15)
				)
			)
		)
		(property "MPN" ""
			(at 0 0 0)
			(layer "F.Fab")
			(hide yes)
			(effects
				(font
					(size 1 1)
					(thickness 0.15)
				)
			)
		)
		(property "Manufacturer" ""
			(at 0 0 0)
			(layer "F.Fab")
			(hide yes)
			(effects
				(font
					(size 1 1)
					(thickness 0.15)
				)
			)
		)
		(property "Public" "False"
			(at 0 0 0)
			(layer "F.Fab")
			(hide yes)
			(effects
				(font
					(size 1 1)
					(thickness 0.15)
				)
			)
		)
		(sheetname "KR to SFI #2")
		(sheetfile "kr_sfi.kicad_sch")
		(attr exclude_from_pos_files exclude_from_bom)
		(fp_circle
			(center 0 0)
			(end 0.475 0)
			(stroke
				(width 0.05)
				(type default)
			)
			(fill no)
			(layer "F.CrtYd")
		)
		(pad "1" smd circle
			(at 0 0)
			(size 0.75 0.75)
			(layers "F.Cu" "F.Mask")
			(net 757 "Net-(U45B-LOSB)")
			(pinfunction "1")
			(pintype "passive")
			(teardrops
				(best_length_ratio 0.4)
				(max_length 1)
				(best_width_ratio 0.9)
				(max_width 2)
				(curved_edges yes)
				(filter_ratio 0.9)
				(enabled yes)
				(allow_two_segments yes)
				(prefer_zone_connections yes)
			)
		)
	)
	(footprint "antmicro-footprints:SOT-23-3"
		(layer "F.Cu")
		(at 221.4985 79.51 90)
		(property "Reference" "D19"
			(at -2.7 -1.0895 180)
			(layer "F.SilkS")
			(effects
				(font
					(size 0.7 0.7)
					(thickness 0.15)
				)
				(justify left bottom)
			)
		)
		(property "Value" "BAT54C"
			(at -1.9 2.7 90)
			(layer "F.Fab")
			(effects
				(font
					(size 0.7 0.7)
					(thickness 0.15)
				)
				(justify left bottom)
			)
		)
		(property "Datasheet" "https://diotec.com/request/datasheet/bat54.pdf"
			(at 0 0 90)
			(layer "F.Fab")
			(hide yes)
			(effects
				(font
					(size 1.27 1.27)
					(thickness 0.15)
				)
			)
		)
		(property "Author" "Antmicro"
			(at 301.0085 -141.9885 0)
			(layer "F.Fab")
			(hide yes)
			(effects
				(font
					(size 1 1)
					(thickness 0.15)
				)
			)
		)
		(property "License" "Apache-2.0"
			(at 301.0085 -141.9885 0)
			(layer "F.Fab")
			(hide yes)
			(effects
				(font
					(size 1 1)
					(thickness 0.15)
				)
			)
		)
		(property "MPN" "BAT54C"
			(at 301.0085 -141.9885 0)
			(layer "F.Fab")
			(hide yes)
			(effects
				(font
					(size 1 1)
					(thickness 0.15)
				)
			)
		)
		(property "Manufacturer" "Diotec Semiconductor"
			(at 301.0085 -141.9885 0)
			(layer "F.Fab")
			(hide yes)
			(effects
				(font
					(size 1 1)
					(thickness 0.15)
				)
			)
		)
		(sheetname "Com Express 7 MGMT")
		(sheetfile "com_express_7_mgmt.kicad_sch")
		(attr smd)
		(fp_line
			(start 0.7 -1.5)
			(end -0.7 -1.5)
			(stroke
				(width 0.15)
				(type solid)
			)
			(layer "F.SilkS")
		)
		(fp_line
			(start -0.85 -1.35)
			(end -0.7 -1.5)
			(stroke
				(width 0.15)
				(type solid)
			)
			(layer "F.SilkS")
		)
		(fp_line
			(start -1.45 -1.35)
			(end -0.85 -1.35)
			(stroke
				(width 0.15)
				(type solid)
			)
			(layer "F.SilkS")
		)
		(fp_line
			(start 0.7 -0.4)
			(end 0.7 -1.5)
			(stroke
				(width 0.15)
				(type solid)
			)
			(layer "F.SilkS")
		)
		(fp_line
			(start 0.7 0.4)
			(end 0.7 1.5)
			(stroke
				(width 0.15)
				(type solid)
			)
			(layer "F.SilkS")
		)
		(fp_line
			(start 0.7 1.5)
			(end -0.7 1.5)
			(stroke
				(width 0.15)
				(type solid)
			)
			(layer "F.SilkS")
		)
		(fp_line
			(start -0.7 1.5)
			(end -0.7 1.35)
			(stroke
				(width 0.15)
				(type solid)
			)
			(layer "F.SilkS")
		)
		(fp_line
			(start 0.825 -1.6)
			(end 0.825 -0.45)
			(stroke
				(width 0.05)
				(type solid)
			)
			(layer "F.CrtYd")
		)
		(fp_line
			(start -0.9 -1.6)
			(end 0.825 -1.6)
			(stroke
				(width 0.05)
				(type solid)
			)
			(layer "F.CrtYd")
		)
		(fp_line
			(start -0.9 -1.6)
			(end -0.9 -1.4)
			(stroke
				(width 0.05)
				(type solid)
			)
			(layer "F.CrtYd")
		)
		(fp_line
			(start -0.9 -1.4)
			(end -1.75 -1.4)
			(stroke
				(width 0.05)
				(type solid)
			)
			(layer "F.CrtYd")
		)
		(fp_line
			(start -0.85 -0.5)
			(end -1.75 -0.5)
			(stroke
				(width 0.05)
				(type solid)
			)
			(layer "F.CrtYd")
		)
		(fp_line
			(start -1.75 -0.5)
			(end -1.75 -1.4)
			(stroke
				(width 0.05)
				(type solid)
			)
			(layer "F.CrtYd")
		)
		(fp_line
			(start 1.75 -0.45)
			(end 1.75 0.45)
			(stroke
				(width 0.05)
				(type solid)
			)
			(layer "F.CrtYd")
		)
		(fp_line
			(start 0.825 -0.45)
			(end 1.75 -0.45)
			(stroke
				(width 0.05)
				(type solid)
			)
			(layer "F.CrtYd")
		)
		(fp_line
			(start 1.75 0.45)
			(end 0.85 0.45)
			(stroke
				(width 0.05)
				(type solid)
			)
			(layer "F.CrtYd")
		)
		(fp_line
			(start 0.85 0.45)
			(end 0.85 1.65)
			(stroke
				(width 0.05)
				(type solid)
			)
			(layer "F.CrtYd")
		)
		(fp_line
			(start -0.85 0.5)
			(end -0.85 -0.5)
			(stroke
				(width 0.05)
				(type solid)
			)
			(layer "F.CrtYd")
		)
		(fp_line
			(start -1.75 0.5)
			(end -0.85 0.5)
			(stroke
				(width 0.05)
				(type solid)
			)
			(layer "F.CrtYd")
		)
		(fp_line
			(start -0.85 1.4)
			(end -1.75 1.4)
			(stroke
				(width 0.05)
				(type solid)
			)
			(layer "F.CrtYd")
		)
		(fp_line
			(start -1.75 1.4)
			(end -1.75 0.5)
			(stroke
				(width 0.05)
				(type solid)
			)
			(layer "F.CrtYd")
		)
		(fp_line
			(start 0.85 1.65)
			(end -0.85 1.65)
			(stroke
				(width 0.05)
				(type solid)
			)
			(layer "F.CrtYd")
		)
		(fp_line
			(start -0.85 1.65)
			(end -0.85 1.4)
			(stroke
				(width 0.05)
				(type solid)
			)
			(layer "F.CrtYd")
		)
		(fp_line
			(start -0.437 -1.526)
			(end 0.688 -1.526)
			(stroke
				(width 0.15)
				(type solid)
			)
			(layer "F.Fab")
		)
		(fp_line
			(start -0.437 -1.526)
			(end -0.712 -1.325)
			(stroke
				(width 0.15)
				(type solid)
			)
			(layer "F.Fab")
		)
		(fp_line
			(start -0.712 -1.325)
			(end -0.712 1.523)
			(stroke
				(width 0.15)
				(type solid)
			)
			(layer "F.Fab")
		)
		(fp_line
			(start 0.688 1.519)
			(end 0.688 -1.52)
			(stroke
				(width 0.15)
				(type solid)
			)
			(layer "F.Fab")
		)
		(fp_line
			(start -0.712 1.519)
			(end 0.688 1.519)
			(stroke
				(width 0.15)
				(type solid)
			)
			(layer "F.Fab")
		)
		(pad "1" smd roundrect
			(at -1.1 -0.951 90)
			(size 1 0.6)
			(layers "F.Cu" "F.Mask" "F.Paste")
			(roundrect_rratio 0.15)
			(net 73 "+3V3_AON")
			(pinfunction "1")
			(pintype "passive")
			(teardrops
				(best_length_ratio 0.2)
				(max_length 1)
				(best_width_ratio 0.9)
				(max_width 2)
				(curved_edges yes)
				(filter_ratio 0.9)
				(enabled yes)
				(allow_two_segments yes)
				(prefer_zone_connections yes)
			)
		)
		(pad "2" smd roundrect
			(at -1.1 0.949 90)
			(size 1 0.6)
			(layers "F.Cu" "F.Mask" "F.Paste")
			(roundrect_rratio 0.15)
			(net 73 "+3V3_AON")
			(pinfunction "2")
			(pintype "passive")
			(teardrops
				(best_length_ratio 0.2)
				(max_length 1)
				(best_width_ratio 0.9)
				(max_width 2)
				(curved_edges yes)
				(filter_ratio 0.9)
				(enabled yes)
				(allow_two_segments yes)
				(prefer_zone_connections yes)
			)
		)
		(pad "3" smd roundrect
			(at 1.1 -0.0005 90)
			(size 1 0.6)
			(layers "F.Cu" "F.Mask" "F.Paste")
			(roundrect_rratio 0.15)
			(net 135 "Net-(D19-Pad3)")
			(pinfunction "3")
			(pintype "passive")
			(teardrops
				(best_length_ratio 0.2)
				(max_length 1)
				(best_width_ratio 0.9)
				(max_width 2)
				(curved_edges yes)
				(filter_ratio 0.9)
				(enabled yes)
				(allow_two_segments yes)
				(prefer_zone_connections yes)
			)
		)
	)
	(footprint "antmicro-footprints:R_0402_1005Metric"
		(layer "F.Cu")
		(at 178.4 147 180)
		(descr "Resistor SMD 0402")
		(tags "resistor SMD 0402")
		(property "Reference" "R38"
			(at -2.95 -0.45 0)
			(layer "F.SilkS")
			(effects
				(font
					(size 0.7 0.7)
					(thickness 0.15)
				)
				(justify right bottom)
			)
		)
		(property "Value" "R_0R_0402"
			(at -1.011843 1.772046 0)
			(layer "F.Fab")
			(effects
				(font
					(size 0.7 0.7)
					(thickness 0.15)
				)
				(justify right bottom)
			)
		)
		(property "Datasheet" "https://industrial.panasonic.com/cdbs/www-data/pdf/RDA0000/AOA0000C301.pdf"
			(at 0 0 0)
			(layer "F.Fab")
			(hide yes)
			(effects
				(font
					(size 1.27 1.27)
					(thickness 0.15)
				)
			)
		)
		(property "Author" "Antmicro"
			(at 337.9 338.52 0)
			(layer "F.Fab")
			(hide yes)
			(effects
				(font
					(size 1 1)
					(thickness 0.15)
				)
			)
		)
		(property "Current" "1A"
			(at 337.9 338.52 0)
			(layer "F.Fab")
			(hide yes)
			(effects
				(font
					(size 1 1)
					(thickness 0.15)
				)
			)
		)
		(property "License" "Apache-2.0"
			(at 337.9 338.52 0)
			(layer "F.Fab")
			(hide yes)
			(effects
				(font
					(size 1 1)
					(thickness 0.15)
				)
			)
		)
		(property "MPN" "ERJ2GE0R00X"
			(at 337.9 338.52 0)
			(layer "F.Fab")
			(hide yes)
			(effects
				(font
					(size 1 1)
					(thickness 0.15)
				)
			)
		)
		(property "Manufacturer" "Panasonic"
			(at 337.9 338.52 0)
			(layer "F.Fab")
			(hide yes)
			(effects
				(font
					(size 1 1)
					(thickness 0.15)
				)
			)
		)
		(property "Public" "False"
			(at 337.9 338.52 0)
			(layer "F.Fab")
			(hide yes)
			(effects
				(font
					(size 1 1)
					(thickness 0.15)
				)
			)
		)
		(property "Tolerance" ""
			(at 337.9 338.52 0)
			(layer "F.Fab")
			(hide yes)
			(effects
				(font
					(size 1 1)
					(thickness 0.15)
				)
			)
		)
		(property "Val" "0R"
			(at 337.9 338.52 0)
			(layer "F.Fab")
			(hide yes)
			(effects
				(font
					(size 1 1)
					(thickness 0.15)
				)
			)
		)
		(sheetname "2xSFP+")
		(sheetfile "2xSFP+.kicad_sch")
		(attr smd)
		(fp_rect
			(start -0.925 -0.47)
			(end 0.925 0.47)
			(stroke
				(width 0.05)
				(type default)
			)
			(fill no)
			(layer "F.CrtYd")
		)
		(fp_rect
			(start -0.5 -0.25)
			(end 0.5 0.25)
			(stroke
				(width 0.15)
				(type solid)
			)
			(fill no)
			(layer "F.Fab")
		)
		(pad "1" smd roundrect
			(at -0.48 0 180)
			(size 0.59 0.64)
			(layers "F.Cu" "F.Mask" "F.Paste")
			(roundrect_rratio 0.25)
			(net 488 "/2xSFP+/I2C_{SFP0}.SCL")
			(pintype "passive")
			(teardrops
				(best_length_ratio 0.2)
				(max_length 1)
				(best_width_ratio 0.9)
				(max_width 2)
				(curved_edges yes)
				(filter_ratio 0.9)
				(enabled yes)
				(allow_two_segments yes)
				(prefer_zone_connections yes)
			)
		)
		(pad "2" smd roundrect
			(at 0.48 0 180)
			(size 0.59 0.64)
			(layers "F.Cu" "F.Mask" "F.Paste")
			(roundrect_rratio 0.25)
			(net 165 "/2xSFP+/SCL0")
			(pintype "passive")
			(teardrops
				(best_length_ratio 0.2)
				(max_length 1)
				(best_width_ratio 0.9)
				(max_width 2)
				(curved_edges yes)
				(filter_ratio 0.9)
				(enabled yes)
				(allow_two_segments yes)
				(prefer_zone_connections yes)
			)
		)
	)
	(footprint "antmicro-footprints:R_0402_1005Metric"
		(layer "F.Cu")
		(at 178.35 103.87 90)
		(descr "Resistor SMD 0402")
		(tags "resistor SMD 0402")
		(property "Reference" "R121"
			(at 0.81 0.45 90)
			(layer "F.SilkS")
			(effects
				(font
					(size 0.7 0.7)
					(thickness 0.15)
				)
				(justify left bottom)
			)
		)
		(property "Value" "R_10k_0402"
			(at -1.011843 1.772047 90)
			(layer "F.Fab")
			(effects
				(font
					(size 0.7 0.7)
					(thickness 0.15)
				)
				(justify left bottom)
			)
		)
		(property "Datasheet" "https://www.bourns.com/docs/product-datasheets/cr.pdf"
			(at 0 0 90)
			(layer "F.Fab")
			(hide yes)
			(effects
				(font
					(size 1.27 1.27)
					(thickness 0.15)
				)
			)
		)
		(property "Author" "Antmicro"
			(at 282.22 -74.48 0)
			(layer "F.Fab")
			(hide yes)
			(effects
				(font
					(size 1 1)
					(thickness 0.15)
				)
			)
		)
		(property "License" "Apache-2.0"
			(at 282.22 -74.48 0)
			(layer "F.Fab")
			(hide yes)
			(effects
				(font
					(size 1 1)
					(thickness 0.15)
				)
			)
		)
		(property "MPN" "CR0402-FX-1002GLF"
			(at 282.22 -74.48 0)
			(layer "F.Fab")
			(hide yes)
			(effects
				(font
					(size 1 1)
					(thickness 0.15)
				)
			)
		)
		(property "Manufacturer" "Bourns"
			(at 282.22 -74.48 0)
			(layer "F.Fab")
			(hide yes)
			(effects
				(font
					(size 1 1)
					(thickness 0.15)
				)
			)
		)
		(property "Public" "False"
			(at 282.22 -74.48 0)
			(layer "F.Fab")
			(hide yes)
			(effects
				(font
					(size 1 1)
					(thickness 0.15)
				)
			)
		)
		(property "Tolerance" "1%"
			(at 282.22 -74.48 0)
			(layer "F.Fab")
			(hide yes)
			(effects
				(font
					(size 1 1)
					(thickness 0.15)
				)
			)
		)
		(property "Val" "10k"
			(at 282.22 -74.48 0)
			(layer "F.Fab")
			(hide yes)
			(effects
				(font
					(size 1 1)
					(thickness 0.15)
				)
			)
		)
		(sheetname "M.2 key M #1")
		(sheetfile "m2keym_low.kicad_sch")
		(attr smd dnp)
		(fp_rect
			(start -0.925 -0.47)
			(end 0.925 0.47)
			(stroke
				(width 0.05)
				(type default)
			)
			(fill no)
			(layer "F.CrtYd")
		)
		(fp_rect
			(start -0.5 -0.25)
			(end 0.5 0.25)
			(stroke
				(width 0.15)
				(type solid)
			)
			(fill no)
			(layer "F.Fab")
		)
		(pad "1" smd roundrect
			(at -0.48 0 90)
			(size 0.59 0.64)
			(layers "F.Cu" "F.Mask" "F.Paste")
			(roundrect_rratio 0.25)
			(net 228 "/M.2 key M #1/~{PERST_D}")
			(pintype "passive")
			(teardrops
				(best_length_ratio 0.2)
				(max_length 1)
				(best_width_ratio 0.9)
				(max_width 2)
				(curved_edges yes)
				(filter_ratio 0.9)
				(enabled yes)
				(allow_two_segments yes)
				(prefer_zone_connections yes)
			)
		)
		(pad "2" smd roundrect
			(at 0.48 0 90)
			(size 0.59 0.64)
			(layers "F.Cu" "F.Mask" "F.Paste")
			(roundrect_rratio 0.25)
			(net 2 "+3V3")
			(pintype "passive")
			(teardrops
				(best_length_ratio 0.2)
				(max_length 1)
				(best_width_ratio 0.9)
				(max_width 2)
				(curved_edges yes)
				(filter_ratio 0.9)
				(enabled yes)
				(allow_two_segments yes)
				(prefer_zone_connections yes)
			)
		)
	)
	(footprint "antmicro-footprints:R_0402_1005Metric"
		(layer "F.Cu")
		(at 178.4 145 180)
		(descr "Resistor SMD 0402")
		(tags "resistor SMD 0402")
		(property "Reference" "R39"
			(at -2.95 -0.45 0)
			(layer "F.SilkS")
			(effects
				(font
					(size 0.7 0.7)
					(thickness 0.15)
				)
				(justify right bottom)
			)
		)
		(property "Value" "R_0R_0402"
			(at -1.011843 1.772046 0)
			(layer "F.Fab")
			(effects
				(font
					(size 0.7 0.7)
					(thickness 0.15)
				)
				(justify right bottom)
			)
		)
		(property "Datasheet" "https://industrial.panasonic.com/cdbs/www-data/pdf/RDA0000/AOA0000C301.pdf"
			(at 0 0 0)
			(layer "F.Fab")
			(hide yes)
			(effects
				(font
					(size 1.27 1.27)
					(thickness 0.15)
				)
			)
		)
		(property "Author" "Antmicro"
			(at 337.899999 332.52 0)
			(layer "F.Fab")
			(hide yes)
			(effects
				(font
					(size 1 1)
					(thickness 0.15)
				)
			)
		)
		(property "Current" "1A"
			(at 337.899999 332.52 0)
			(layer "F.Fab")
			(hide yes)
			(effects
				(font
					(size 1 1)
					(thickness 0.15)
				)
			)
		)
		(property "License" "Apache-2.0"
			(at 337.899999 332.52 0)
			(layer "F.Fab")
			(hide yes)
			(effects
				(font
					(size 1 1)
					(thickness 0.15)
				)
			)
		)
		(property "MPN" "ERJ2GE0R00X"
			(at 337.899999 332.52 0)
			(layer "F.Fab")
			(hide yes)
			(effects
				(font
					(size 1 1)
					(thickness 0.15)
				)
			)
		)
		(property "Manufacturer" "Panasonic"
			(at 337.899999 332.52 0)
			(layer "F.Fab")
			(hide yes)
			(effects
				(font
					(size 1 1)
					(thickness 0.15)
				)
			)
		)
		(property "Public" "False"
			(at 337.899999 332.52 0)
			(layer "F.Fab")
			(hide yes)
			(effects
				(font
					(size 1 1)
					(thickness 0.15)
				)
			)
		)
		(property "Tolerance" ""
			(at 337.899999 332.52 0)
			(layer "F.Fab")
			(hide yes)
			(effects
				(font
					(size 1 1)
					(thickness 0.15)
				)
			)
		)
		(property "Val" "0R"
			(at 337.899999 332.52 0)
			(layer "F.Fab")
			(hide yes)
			(effects
				(font
					(size 1 1)
					(thickness 0.15)
				)
			)
		)
		(sheetname "2xSFP+")
		(sheetfile "2xSFP+.kicad_sch")
		(attr smd)
		(fp_rect
			(start -0.925 -0.47)
			(end 0.925 0.47)
			(stroke
				(width 0.05)
				(type default)
			)
			(fill no)
			(layer "F.CrtYd")
		)
		(fp_rect
			(start -0.5 -0.25)
			(end 0.5 0.25)
			(stroke
				(width 0.15)
				(type solid)
			)
			(fill no)
			(layer "F.Fab")
		)
		(pad "1" smd roundrect
			(at -0.48 0 180)
			(size 0.59 0.64)
			(layers "F.Cu" "F.Mask" "F.Paste")
			(roundrect_rratio 0.25)
			(net 431 "/2xSFP+/MOD0_ABS")
			(pintype "passive")
			(teardrops
				(best_length_ratio 0.2)
				(max_length 1)
				(best_width_ratio 0.9)
				(max_width 2)
				(curved_edges yes)
				(filter_ratio 0.9)
				(enabled yes)
				(allow_two_segments yes)
				(prefer_zone_connections yes)
			)
		)
		(pad "2" smd roundrect
			(at 0.48 0 180)
			(size 0.59 0.64)
			(layers "F.Cu" "F.Mask" "F.Paste")
			(roundrect_rratio 0.25)
			(net 166 "Net-(J2A-MOD_{ABS})")
			(pintype "passive")
			(teardrops
				(best_length_ratio 0.2)
				(max_length 1)
				(best_width_ratio 0.9)
				(max_width 2)
				(curved_edges yes)
				(filter_ratio 0.9)
				(enabled yes)
				(allow_two_segments yes)
				(prefer_zone_connections yes)
			)
		)
	)
)
